# T6G (Grand Teton) — schematic netlist excerpt (pin names and nets, part order shuffled) for the footprints in the layout excerpt that follows; sources: Cadence DE-HDL packaged netlist, KiCad conversion of 04192023_DAF0TMB3IC0_F0TG_MB_C_brd_V02_OCP.brd

R880  Q_RES  4.7K 5% EMPTY  pkg 0201LF  page 342 : A = P1V8_CPU1_RT_1D ; B = TEST1_RT_CPU1_P2
R308  Q_RES  33 5% CHIP  pkg 0402LF  page 151 : A = SMB_VR_3V3AUX_SCL ; B = SMB_VR_3V3STBY_SCL
R1592  Q_RES  33 5% CHIP  pkg 0402LF  page 29 : A = ESPI_CPU0_CS1_N ; B = CPU0_ESPI_CS0_N

(kicad_pcb
	(version 20260206)
	(generator "pcbnew")
	(generator_version "10.0")
	(general
		(thickness 1.6)
		(legacy_teardrops no)
	)
	(paper "A4")
	(title_block
		(title "04192023_DAF0TMB3IC0_F0TG_MB_C_brd_V02_OCP.brd")
		(comment 1 "Grand Teton / footprints 6463-6465 of 8354")
	)
	(layers
		(0 "F.Cu" signal "TOP")
		(4 "In1.Cu" signal "GND")
		(6 "In2.Cu" signal "IN1")
		(8 "In3.Cu" signal "GND1")
		(10 "In4.Cu" signal "IN2")
		(12 "In5.Cu" signal "GND2")
		(14 "In6.Cu" signal "IN3")
		(16 "In7.Cu" signal "GND3")
		(18 "In8.Cu" signal "VCC")
		(20 "In9.Cu" signal "VCC1")
		(22 "In10.Cu" signal "GND4")
		(24 "In11.Cu" signal "IN4")
		(26 "In12.Cu" signal "GND5")
		(28 "In13.Cu" signal "IN5")
		(30 "In14.Cu" signal "GND6")
		(32 "In15.Cu" signal "IN6")
		(34 "In16.Cu" signal "GND7")
		(2 "B.Cu" signal "BOTTOM")
		(9 "F.Adhes" user "F.Adhesive")
		(11 "B.Adhes" user "B.Adhesive")
		(13 "F.Paste" user "Package Geometry/Pastemask Top")
		(15 "B.Paste" user "Package Geometry/Pastemask Bottom")
		(5 "F.SilkS" user "Ref Des/Silkscreen Top")
		(7 "B.SilkS" user "Ref Des/Silkscreen Bottom")
		(1 "F.Mask" user "Board Geometry/Soldermask Top")
		(3 "B.Mask" user "Board Geometry/Soldermask Bottom")
		(17 "Dwgs.User" user "User.Drawings")
		(19 "Cmts.User" user "User.Comments")
		(21 "Eco1.User" user "User.Eco1")
		(23 "Eco2.User" user "User.Eco2")
		(25 "Edge.Cuts" user "Board Geometry/Outline")
		(27 "Margin" user)
		(31 "F.CrtYd" user "Package Geometry/Place Bound Top")
		(29 "B.CrtYd" user "Package Geometry/Place Bound Bottom")
		(35 "F.Fab" user "Ref Des/Assembly Top")
		(33 "B.Fab" user "Ref Des/Assembly Bottom")
	)
	(footprint ""
		(layer "B.Cu")
		(at 141.623542 -384.66268 180)
		(property "Reference" "R880"
			(at 0 0 0)
			(layer "B.SilkS")
			(hide yes)
			(effects
				(font
					(size 1.27 1.27)
				)
				(justify mirror)
			)
		)
		(property "Value" ""
			(at 0 0 0)
			(layer "B.Fab")
			(effects
				(font
					(size 1.27 1.27)
				)
				(justify mirror)
			)
		)
		(duplicate_pad_numbers_are_jumpers no)
		(fp_line
			(start 0.32512 0.175006)
			(end 0.32512 -0.175006)
			(stroke
				(width 0.1)
				(type default)
			)
			(layer "B.Fab")
		)
		(fp_line
			(start 0.32512 -0.175006)
			(end -0.32512 -0.175006)
			(stroke
				(width 0.1)
				(type default)
			)
			(layer "B.Fab")
		)
		(fp_line
			(start -0.32512 0.175006)
			(end 0.32512 0.175006)
			(stroke
				(width 0.1)
				(type default)
			)
			(layer "B.Fab")
		)
		(fp_line
			(start -0.32512 -0.175006)
			(end -0.32512 0.175006)
			(stroke
				(width 0.1)
				(type default)
			)
			(layer "B.Fab")
		)
		(pad "1" smd rect
			(at 0.2667 0)
			(size 0.3048 0.381)
			(layers "B.Cu" "B.Mask" "B.Paste")
			(net "P1V8_CPU1_RT_1D")
		)
		(pad "2" smd rect
			(at -0.2667 0 180)
			(size 0.3048 0.381)
			(layers "B.Cu" "B.Mask" "B.Paste")
			(net "TEST1_RT_CPU1_P2")
		)
	)
	(footprint ""
		(layer "B.Cu")
		(at 398.680178 -324.812152 180)
		(property "Reference" "R1592"
			(at 0 0 0)
			(layer "B.SilkS")
			(hide yes)
			(effects
				(font
					(size 1.27 1.27)
				)
				(justify mirror)
			)
		)
		(property "Value" ""
			(at 0 0 0)
			(layer "B.Fab")
			(effects
				(font
					(size 1.27 1.27)
				)
				(justify mirror)
			)
		)
		(duplicate_pad_numbers_are_jumpers no)
		(fp_line
			(start 0.7874 0.4064)
			(end 0.7874 -0.4064)
			(stroke
				(width 0.1524)
				(type default)
			)
			(layer "B.SilkS")
		)
		(fp_line
			(start 0.7874 -0.4064)
			(end -0.7874 -0.4064)
			(stroke
				(width 0.1524)
				(type default)
			)
			(layer "B.SilkS")
		)
		(fp_line
			(start -0.7874 0.4064)
			(end 0.7874 0.4064)
			(stroke
				(width 0.1524)
				(type default)
			)
			(layer "B.SilkS")
		)
		(fp_line
			(start -0.7874 -0.4064)
			(end -0.7874 0.4064)
			(stroke
				(width 0.1524)
				(type default)
			)
			(layer "B.SilkS")
		)
		(fp_line
			(start 0.67945 0.3048)
			(end 0.67945 -0.305054)
			(stroke
				(width 0.1)
				(type default)
			)
			(layer "B.Fab")
		)
		(fp_line
			(start 0.67945 -0.305054)
			(end 0.12065 -0.305054)
			(stroke
				(width 0.1)
				(type default)
			)
			(layer "B.Fab")
		)
		(fp_line
			(start 0.12065 0.3048)
			(end 0.67945 0.3048)
			(stroke
				(width 0.1)
				(type default)
			)
			(layer "B.Fab")
		)
		(fp_line
			(start 0.12065 0.2794)
			(end 0.12065 0.3048)
			(stroke
				(width 0.1)
				(type default)
			)
			(layer "B.Fab")
		)
		(fp_line
			(start 0.12065 -0.2794)
			(end -0.12065 -0.2794)
			(stroke
				(width 0.1)
				(type default)
			)
			(layer "B.Fab")
		)
		(fp_line
			(start 0.12065 -0.305054)
			(end 0.12065 -0.2794)
			(stroke
				(width 0.1)
				(type default)
			)
			(layer "B.Fab")
		)
		(fp_line
			(start -0.120396 0.3048)
			(end -0.120396 0.2794)
			(stroke
				(width 0.1)
				(type default)
			)
			(layer "B.Fab")
		)
		(fp_line
			(start -0.120396 0.2794)
			(end 0.12065 0.2794)
			(stroke
				(width 0.1)
				(type default)
			)
			(layer "B.Fab")
		)
		(fp_line
			(start -0.12065 -0.2794)
			(end -0.12065 -0.3048)
			(stroke
				(width 0.1)
				(type default)
			)
			(layer "B.Fab")
		)
		(fp_line
			(start -0.12065 -0.3048)
			(end -0.67945 -0.3048)
			(stroke
				(width 0.1)
				(type default)
			)
			(layer "B.Fab")
		)
		(fp_line
			(start -0.67945 0.3048)
			(end -0.120396 0.3048)
			(stroke
				(width 0.1)
				(type default)
			)
			(layer "B.Fab")
		)
		(fp_line
			(start -0.67945 -0.3048)
			(end -0.67945 0.3048)
			(stroke
				(width 0.1)
				(type default)
			)
			(layer "B.Fab")
		)
		(pad "1" smd rect
			(at 0.40005 0 180)
			(size 0.4572 0.508)
			(layers "B.Cu" "B.Mask" "B.Paste")
			(net "ESPI_CPU0_CS1_N")
		)
		(pad "2" smd rect
			(at -0.40005 0 180)
			(size 0.4572 0.508)
			(layers "B.Cu" "B.Mask" "B.Paste")
			(net "CPU0_ESPI_CS0_N")
		)
	)
	(footprint ""
		(layer "B.Cu")
		(at 93.4212 -138.176)
		(property "Reference" "R308"
			(at 0 0 0)
			(layer "B.SilkS")
			(hide yes)
			(effects
				(font
					(size 1.27 1.27)
				)
				(justify mirror)
			)
		)
		(property "Value" ""
			(at 0 0 0)
			(layer "B.Fab")
			(effects
				(font
					(size 1.27 1.27)
				)
				(justify mirror)
			)
		)
		(duplicate_pad_numbers_are_jumpers no)
		(fp_line
			(start -0.7874 -0.4064)
			(end -0.7874 0.4064)
			(stroke
				(width 0.1524)
				(type default)
			)
			(layer "B.SilkS")
		)
		(fp_line
			(start -0.7874 0.4064)
			(end 0.7874 0.4064)
			(stroke
				(width 0.1524)
				(type default)
			)
			(layer "B.SilkS")
		)
		(fp_line
			(start 0.7874 -0.4064)
			(end -0.7874 -0.4064)
			(stroke
				(width 0.1524)
				(type default)
			)
			(layer "B.SilkS")
		)
		(fp_line
			(start 0.7874 0.4064)
			(end 0.7874 -0.4064)
			(stroke
				(width 0.1524)
				(type default)
			)
			(layer "B.SilkS")
		)
		(fp_line
			(start -0.67945 -0.3048)
			(end -0.67945 0.3048)
			(stroke
				(width 0.1)
				(type default)
			)
			(layer "B.Fab")
		)
		(fp_line
			(start -0.67945 0.3048)
			(end -0.120396 0.3048)
			(stroke
				(width 0.1)
				(type default)
			)
			(layer "B.Fab")
		)
		(fp_line
			(start -0.12065 -0.3048)
			(end -0.67945 -0.3048)
			(stroke
				(width 0.1)
				(type default)
			)
			(layer "B.Fab")
		)
		(fp_line
			(start -0.12065 -0.2794)
			(end -0.12065 -0.3048)
			(stroke
				(width 0.1)
				(type default)
			)
			(layer "B.Fab")
		)
		(fp_line
			(start -0.120396 0.2794)
			(end 0.12065 0.2794)
			(stroke
				(width 0.1)
				(type default)
			)
			(layer "B.Fab")
		)
		(fp_line
			(start -0.120396 0.3048)
			(end -0.120396 0.2794)
			(stroke
				(width 0.1)
				(type default)
			)
			(layer "B.Fab")
		)
		(fp_line
			(start 0.12065 -0.305054)
			(end 0.12065 -0.2794)
			(stroke
				(width 0.1)
				(type default)
			)
			(layer "B.Fab")
		)
		(fp_line
			(start 0.12065 -0.2794)
			(end -0.12065 -0.2794)
			(stroke
				(width 0.1)
				(type default)
			)
			(layer "B.Fab")
		)
		(fp_line
			(start 0.12065 0.2794)
			(end 0.12065 0.3048)
			(stroke
				(width 0.1)
				(type default)
			)
			(layer "B.Fab")
		)
		(fp_line
			(start 0.12065 0.3048)
			(end 0.67945 0.3048)
			(stroke
				(width 0.1)
				(type default)
			)
			(layer "B.Fab")
		)
		(fp_line
			(start 0.67945 -0.305054)
			(end 0.12065 -0.305054)
			(stroke
				(width 0.1)
				(type default)
			)
			(layer "B.Fab")
		)
		(fp_line
			(start 0.67945 0.3048)
			(end 0.67945 -0.305054)
			(stroke
				(width 0.1)
				(type default)
			)
			(layer "B.Fab")
		)
		(pad "1" smd circle
			(at 0.40005 0 180)
			(size 0 0)
			(layers "B.Cu" "B.Mask" "B.Paste")
			(net "SMB_VR_3V3AUX_SCL")
		)
		(pad "2" smd circle
			(at -0.40005 0 180)
			(size 0 0)
			(layers "B.Cu" "B.Mask" "B.Paste")
			(net "SMB_VR_3V3STBY_SCL")
		)
	)
)
